(kicad_pcb
	(version 20241229)
	(generator "pcbnew")
	(generator_version "9.0")
	(general
		(thickness 1.6)
		(legacy_teardrops no)
	)
	(paper "A4")
	(title_block
		(title "OCuLink to PCIe adapter")
		(date "2025-06-18")
		(rev "1.0.0")
		(company "Antmicro Ltd")
		(comment 1 "www.antmicro.com")
		(comment 9 "footprints 91-95 of 159")
	)
	(layers
		(0 "F.Cu" signal)
		(4 "In1.Cu" signal)
		(6 "In2.Cu" signal)
		(2 "B.Cu" signal)
		(9 "F.Adhes" user "F.Adhesive")
		(11 "B.Adhes" user "B.Adhesive")
		(13 "F.Paste" user)
		(15 "B.Paste" user)
		(5 "F.SilkS" user "F.Silkscreen")
		(7 "B.SilkS" user "B.Silkscreen")
		(1 "F.Mask" user)
		(3 "B.Mask" user)
		(17 "Dwgs.User" user "User.Drawings")
		(19 "Cmts.User" user "User.Comments")
		(21 "Eco1.User" user "User.Eco1")
		(23 "Eco2.User" user "User.Eco2")
		(25 "Edge.Cuts" user)
		(27 "Margin" user)
		(31 "F.CrtYd" user "F.Courtyard")
		(29 "B.CrtYd" user "B.Courtyard")
		(35 "F.Fab" user)
		(33 "B.Fab" user)
	)
	(footprint "antmicro-footprints:R_0402_1005Metric"
		(layer "F.Cu")
		(at 138.899999 68.05 90)
		(descr "Resistor SMD 0402")
		(tags "resistor SMD 0402")
		(property "Reference" "R35"
			(at 1.299999 -5.649499 90)
			(layer "F.SilkS")
			(effects
				(font
					(size 0.7 0.7)
					(thickness 0.15)
				)
				(justify right top)
			)
		)
		(property "Value" "R_68k_0402"
			(at -1.011843 1.772046 90)
			(layer "F.Fab")
			(effects
				(font
					(size 0.7 0.7)
					(thickness 0.15)
				)
				(justify left bottom)
			)
		)
		(property "Datasheet" "https://www.bourns.com/docs/product-datasheets/cr.pdf"
			(at 0 0 90)
			(layer "F.Fab")
			(hide yes)
			(effects
				(font
					(size 1.27 1.27)
					(thickness 0.15)
				)
			)
		)
		(property "Description" "SMD Chip Resistor"
			(at 0 0 90)
			(layer "F.Fab")
			(hide yes)
			(effects
				(font
					(size 1.27 1.27)
					(thickness 0.15)
				)
			)
		)
		(property "MPN" "CR0402-FX-6802GLF"
			(at 0 0 90)
			(unlocked yes)
			(layer "F.Fab")
			(hide yes)
			(effects
				(font
					(size 1 1)
					(thickness 0.15)
				)
			)
		)
		(property "Manufacturer" "Bourns"
			(at 0 0 90)
			(unlocked yes)
			(layer "F.Fab")
			(hide yes)
			(effects
				(font
					(size 1 1)
					(thickness 0.15)
				)
			)
		)
		(property "License" "Apache-2.0"
			(at 0 0 90)
			(unlocked yes)
			(layer "F.Fab")
			(hide yes)
			(effects
				(font
					(size 1 1)
					(thickness 0.15)
				)
			)
		)
		(property "Author" "Antmicro"
			(at 0 0 90)
			(unlocked yes)
			(layer "F.Fab")
			(hide yes)
			(effects
				(font
					(size 1 1)
					(thickness 0.15)
				)
			)
		)
		(property "Val" "68k"
			(at 0 0 90)
			(unlocked yes)
			(layer "F.Fab")
			(hide yes)
			(effects
				(font
					(size 1 1)
					(thickness 0.15)
				)
			)
		)
		(property "Tolerance" "1%"
			(at 0 0 90)
			(unlocked yes)
			(layer "F.Fab")
			(hide yes)
			(effects
				(font
					(size 1 1)
					(thickness 0.15)
				)
			)
		)
		(sheetname "/USB-PD/")
		(sheetfile "usb-pd.kicad_sch")
		(attr smd)
		(fp_rect
			(start -0.925 -0.47)
			(end 0.925 0.47)
			(stroke
				(width 0.05)
				(type default)
			)
			(fill no)
			(layer "F.CrtYd")
		)
		(fp_rect
			(start -0.5 -0.25)
			(end 0.5 0.25)
			(stroke
				(width 0.15)
				(type solid)
			)
			(fill no)
			(layer "F.Fab")
		)
		(fp_text user "Author: Antmicro"
			(at -0.95 4.169 90)
			(layer "F.Fab")
			(effects
				(font
					(size 0.7 0.7)
					(thickness 0.15)
				)
				(justify left bottom)
			)
		)
		(fp_text user "${REFERENCE}"
			(at 0 0 270)
			(layer "F.Fab")
			(effects
				(font
					(size 0.7 0.7)
					(thickness 0.15)
				)
				(justify right top)
			)
		)
		(fp_text user "License: Apache-2.0"
			(at -0.949999 5.169 90)
			(layer "F.Fab")
			(effects
				(font
					(size 0.7 0.7)
					(thickness 0.15)
				)
				(justify left bottom)
			)
		)
		(pad "1" smd roundrect
			(at -0.48 0 90)
			(size 0.59 0.64)
			(layers "F.Cu" "F.Mask" "F.Paste")
			(roundrect_rratio 0.25)
			(net 174 "Net-(Q4-D)")
			(pintype "passive")
		)
		(pad "2" smd roundrect
			(at 0.48 0 90)
			(size 0.59 0.64)
			(layers "F.Cu" "F.Mask" "F.Paste")
			(roundrect_rratio 0.25)
			(net 165 "Net-(D4-C_{G})")
			(pintype "passive")
		)
	)
	(footprint "antmicro-footprints:R_0402_1005Metric"
		(layer "F.Cu")
		(at 147.737 57.376001 90)
		(descr "Resistor SMD 0402")
		(tags "resistor SMD 0402")
		(property "Reference" "R17"
			(at -3.273999 0.439001 90)
			(layer "F.SilkS")
			(effects
				(font
					(size 0.7 0.7)
					(thickness 0.15)
				)
				(justify left bottom)
			)
		)
		(property "Value" "R_1k_0402"
			(at -1.011843 1.772046 90)
			(layer "F.Fab")
			(effects
				(font
					(size 0.7 0.7)
					(thickness 0.15)
				)
				(justify left bottom)
			)
		)
		(property "Datasheet" "https://www.bourns.com/docs/product-datasheets/cr.pdf"
			(at 0 0 90)
			(layer "F.Fab")
			(hide yes)
			(effects
				(font
					(size 1.27 1.27)
					(thickness 0.15)
				)
			)
		)
		(property "Description" "SMD Chip Resistor, 1 kohm, ± 1%, 63 mW, 0402 [1005 Metric], Thick Film, General Purpose"
			(at 0 0 90)
			(layer "F.Fab")
			(hide yes)
			(effects
				(font
					(size 1.27 1.27)
					(thickness 0.15)
				)
			)
		)
		(property "MPN" "CR0402-FX-1001GLF"
			(at 0 0 90)
			(unlocked yes)
			(layer "F.Fab")
			(hide yes)
			(effects
				(font
					(size 1 1)
					(thickness 0.15)
				)
			)
		)
		(property "Manufacturer" "Bourns"
			(at 0 0 90)
			(unlocked yes)
			(layer "F.Fab")
			(hide yes)
			(effects
				(font
					(size 1 1)
					(thickness 0.15)
				)
			)
		)
		(property "License" "Apache-2.0"
			(at 0 0 90)
			(unlocked yes)
			(layer "F.Fab")
			(hide yes)
			(effects
				(font
					(size 1 1)
					(thickness 0.15)
				)
			)
		)
		(property "Author" "Antmicro"
			(at 0 0 90)
			(unlocked yes)
			(layer "F.Fab")
			(hide yes)
			(effects
				(font
					(size 1 1)
					(thickness 0.15)
				)
			)
		)
		(property "Val" "1k"
			(at 0 0 90)
			(unlocked yes)
			(layer "F.Fab")
			(hide yes)
			(effects
				(font
					(size 1 1)
					(thickness 0.15)
				)
			)
		)
		(property "Tolerance" "1%"
			(at 0 0 90)
			(unlocked yes)
			(layer "F.Fab")
			(hide yes)
			(effects
				(font
					(size 1 1)
					(thickness 0.15)
				)
			)
		)
		(sheetname "/USB-PD/")
		(sheetfile "usb-pd.kicad_sch")
		(attr smd exclude_from_bom dnp)
		(fp_rect
			(start -0.925 -0.47)
			(end 0.925 0.47)
			(stroke
				(width 0.05)
				(type default)
			)
			(fill no)
			(layer "F.CrtYd")
		)
		(fp_rect
			(start -0.5 -0.25)
			(end 0.5 0.25)
			(stroke
				(width 0.15)
				(type solid)
			)
			(fill no)
			(layer "F.Fab")
		)
		(fp_text user "License: Apache-2.0"
			(at -0.949999 5.169 90)
			(layer "F.Fab")
			(effects
				(font
					(size 0.7 0.7)
					(thickness 0.15)
				)
				(justify left bottom)
			)
		)
		(fp_text user "${REFERENCE}"
			(at 0 0 90)
			(layer "F.Fab")
			(effects
				(font
					(size 0.7 0.7)
					(thickness 0.15)
				)
				(justify left bottom)
			)
		)
		(fp_text user "Author: Antmicro"
			(at -0.95 4.169 90)
			(layer "F.Fab")
			(effects
				(font
					(size 0.7 0.7)
					(thickness 0.15)
				)
				(justify left bottom)
			)
		)
		(pad "1" smd roundrect
			(at -0.48 0 90)
			(size 0.59 0.64)
			(layers "F.Cu" "F.Mask" "F.Paste")
			(roundrect_rratio 0.25)
			(net 66 "GND")
			(pintype "passive")
		)
		(pad "2" smd roundrect
			(at 0.48 0 90)
			(size 0.59 0.64)
			(layers "F.Cu" "F.Mask" "F.Paste")
			(roundrect_rratio 0.25)
			(net 133 "/USB-PD/VBUS_MIN")
			(pintype "passive")
		)
	)
	(footprint "antmicro-footprints:R_0402_1005Metric"
		(layer "F.Cu")
		(at 154.312 52.001)
		(descr "Resistor SMD 0402")
		(tags "resistor SMD 0402")
		(property "Reference" "R19"
			(at 1.088 0.399 180)
			(layer "F.SilkS")
			(effects
				(font
					(size 0.7 0.7)
					(thickness 0.15)
				)
				(justify left bottom)
			)
		)
		(property "Value" "R_2k_0402"
			(at -1.011843 1.772046 0)
			(layer "F.Fab")
			(effects
				(font
					(size 0.7 0.7)
					(thickness 0.15)
				)
				(justify left bottom)
			)
		)
		(property "Datasheet" "https://www.bourns.com/docs/product-datasheets/cr.pdf"
			(at 0 0 0)
			(layer "F.Fab")
			(hide yes)
			(effects
				(font
					(size 1.27 1.27)
					(thickness 0.15)
				)
			)
		)
		(property "Description" "SMD Chip Resistor, 2 kohm, ± 1%, 62.5 mW, 0402 [1005 Metric], Thick Film, General Purpose"
			(at 0 0 0)
			(layer "F.Fab")
			(hide yes)
			(effects
				(font
					(size 1.27 1.27)
					(thickness 0.15)
				)
			)
		)
		(property "MPN" "CR0402-FX-2001GLF"
			(at 0 0 0)
			(unlocked yes)
			(layer "F.Fab")
			(hide yes)
			(effects
				(font
					(size 1 1)
					(thickness 0.15)
				)
			)
		)
		(property "Manufacturer" "Bourns"
			(at 0 0 0)
			(unlocked yes)
			(layer "F.Fab")
			(hide yes)
			(effects
				(font
					(size 1 1)
					(thickness 0.15)
				)
			)
		)
		(property "License" "Apache-2.0"
			(at 0 0 0)
			(unlocked yes)
			(layer "F.Fab")
			(hide yes)
			(effects
				(font
					(size 1 1)
					(thickness 0.15)
				)
			)
		)
		(property "Author" "Antmicro"
			(at 0 0 0)
			(unlocked yes)
			(layer "F.Fab")
			(hide yes)
			(effects
				(font
					(size 1 1)
					(thickness 0.15)
				)
			)
		)
		(property "Val" "2k"
			(at 0 0 0)
			(unlocked yes)
			(layer "F.Fab")
			(hide yes)
			(effects
				(font
					(size 1 1)
					(thickness 0.15)
				)
			)
		)
		(property "Tolerance" "1%"
			(at 0 0 0)
			(unlocked yes)
			(layer "F.Fab")
			(hide yes)
			(effects
				(font
					(size 1 1)
					(thickness 0.15)
				)
			)
		)
		(sheetname "/USB-PD/")
		(sheetfile "usb-pd.kicad_sch")
		(attr smd)
		(fp_rect
			(start -0.925 -0.47)
			(end 0.925 0.47)
			(stroke
				(width 0.05)
				(type default)
			)
			(fill no)
			(layer "F.CrtYd")
		)
		(fp_rect
			(start -0.5 -0.25)
			(end 0.5 0.25)
			(stroke
				(width 0.15)
				(type solid)
			)
			(fill no)
			(layer "F.Fab")
		)
		(fp_text user "Author: Antmicro"
			(at -0.95 4.169 0)
			(layer "F.Fab")
			(effects
				(font
					(size 0.7 0.7)
					(thickness 0.15)
				)
				(justify left bottom)
			)
		)
		(fp_text user "${REFERENCE}"
			(at 0 0 0)
			(layer "F.Fab")
			(effects
				(font
					(size 0.7 0.7)
					(thickness 0.15)
				)
				(justify left bottom)
			)
		)
		(fp_text user "License: Apache-2.0"
			(at -0.949999 5.169 0)
			(layer "F.Fab")
			(effects
				(font
					(size 0.7 0.7)
					(thickness 0.15)
				)
				(justify left bottom)
			)
		)
		(pad "1" smd roundrect
			(at -0.48 0)
			(size 0.59 0.64)
			(layers "F.Cu" "F.Mask" "F.Paste")
			(roundrect_rratio 0.25)
			(net 141 "/USB-PD/SDA")
			(pintype "passive")
		)
		(pad "2" smd roundrect
			(at 0.48 0)
			(size 0.59 0.64)
			(layers "F.Cu" "F.Mask" "F.Paste")
			(roundrect_rratio 0.25)
			(net 117 "/USB-PD/VDDD_3V3")
			(pintype "passive")
		)
	)
	(footprint "antmicro-footprints:MP_Pad6mm_Drill3.2mm"
		(layer "F.Cu")
		(at 109 131 -90)
		(property "Reference" "MP5"
			(at 0 0 90)
			(layer "F.SilkS")
			(hide yes)
			(effects
				(font
					(size 0.7 0.7)
					(thickness 0.15)
				)
				(justify right top)
			)
		)
		(property "Value" "MP_Pad6mm_Drill3.2mm"
			(at 0 3.899999 90)
			(layer "F.Fab")
			(effects
				(font
					(size 0.7 0.7)
					(thickness 0.15)
				)
				(justify right top)
			)
		)
		(property "Description" "Mechanical part"
			(at 0 0 90)
			(layer "F.Fab")
			(hide yes)
			(effects
				(font
					(size 1.27 1.27)
					(thickness 0.15)
				)
			)
		)
		(property "Author" "Antmicro"
			(at 0 0 270)
			(unlocked yes)
			(layer "F.Fab")
			(hide yes)
			(effects
				(font
					(size 1 1)
					(thickness 0.15)
				)
			)
		)
		(property "License" "Apache-2.0"
			(at 0 0 270)
			(unlocked yes)
			(layer "F.Fab")
			(hide yes)
			(effects
				(font
					(size 1 1)
					(thickness 0.15)
				)
			)
		)
		(sheetname "/")
		(sheetfile "oculink-to-pcie-adapter.kicad_sch")
		(attr board_only exclude_from_pos_files exclude_from_bom)
		(fp_circle
			(center 0 0)
			(end 3.25 0)
			(stroke
				(width 0.05)
				(type default)
			)
			(fill no)
			(layer "F.CrtYd")
		)
		(fp_text user "${REFERENCE}"
			(at 0 0 90)
			(layer "F.Fab")
			(effects
				(font
					(size 0.7 0.7)
					(thickness 0.15)
				)
				(justify right top)
			)
		)
		(fp_text user "License: Apache-2.0"
			(at -0.178 8.425001 90)
			(layer "F.Fab")
			(effects
				(font
					(size 0.7 0.7)
					(thickness 0.15)
				)
				(justify right top)
			)
		)
		(fp_text user "Author: Antmicro"
			(at -0.178001 7.225 90)
			(layer "F.Fab")
			(effects
				(font
					(size 0.7 0.7)
					(thickness 0.15)
				)
				(justify right top)
			)
		)
		(pad "1" thru_hole circle
			(at 0 0 270)
			(size 6 6)
			(drill 3.2)
			(layers "*.Cu" "*.Mask")
			(remove_unused_layers no)
			(net 66 "GND")
			(pintype "passive")
		)
	)
	(footprint "antmicro-footprints:VQFN-14-1EP_3.2x2.5mm_P0.5mm_Layout4x3"
		(layer "F.Cu")
		(at 140.3 63)
		(property "Reference" "U7"
			(at 0.8 -2.4 0)
			(unlocked yes)
			(layer "F.SilkS")
			(effects
				(font
					(size 0.7 0.7)
					(thickness 0.15)
				)
				(justify left bottom)
			)
		)
		(property "Value" "DSC557-0343FI1"
			(at 0 3.1 0)
			(unlocked yes)
			(layer "F.Fab")
			(effects
				(font
					(size 0.7 0.7)
					(thickness 0.15)
				)
				(justify left bottom)
			)
		)
		(property "Datasheet" "https://ww1.microchip.com/downloads/aemDocuments/documents/TCG/ProductDocuments/DataSheets/DSC557-03-04-05-Multiple-Output-MEMS-PCIe-Gen1-2-3-4-Clock-Generators-DS20006691.pdf"
			(at 0 0 0)
			(layer "F.Fab")
			(hide yes)
			(effects
				(font
					(size 1.27 1.27)
					(thickness 0.15)
				)
			)
		)
		(property "Description" "Two output PCIe Clock Generator"
			(at 0 0 0)
			(layer "F.Fab")
			(hide yes)
			(effects
				(font
					(size 1.27 1.27)
					(thickness 0.15)
				)
			)
		)
		(property "Manufacturer" "Microchip Technology"
			(at 0 0 0)
			(unlocked yes)
			(layer "F.Fab")
			(hide yes)
			(effects
				(font
					(size 1 1)
					(thickness 0.15)
				)
			)
		)
		(property "MPN" "DSC557-0343FI1"
			(at 0 0 0)
			(unlocked yes)
			(layer "F.Fab")
			(hide yes)
			(effects
				(font
					(size 1 1)
					(thickness 0.15)
				)
			)
		)
		(property "Val" "100 MHz"
			(at 0 0 0)
			(unlocked yes)
			(layer "F.Fab")
			(hide yes)
			(effects
				(font
					(size 1 1)
					(thickness 0.15)
				)
			)
		)
		(property "Author" "Antmicro"
			(at 0 0 0)
			(unlocked yes)
			(layer "F.Fab")
			(hide yes)
			(effects
				(font
					(size 1 1)
					(thickness 0.15)
				)
			)
		)
		(property "License" "Apache-2.0"
			(at 0 0 0)
			(unlocked yes)
			(layer "F.Fab")
			(hide yes)
			(effects
				(font
					(size 1 1)
					(thickness 0.15)
				)
			)
		)
		(sheetname "/PCIe-clock-generator/")
		(sheetfile "pcie-clock-generator.kicad_sch")
		(attr smd exclude_from_bom dnp)
		(fp_circle
			(center -1.5 -1.075)
			(end -1.45 -1.075)
			(stroke
				(width 0.15)
				(type solid)
			)
			(fill yes)
			(layer "F.SilkS")
		)
		(fp_rect
			(start -1.746 -2.101)
			(end 1.745 2.1)
			(stroke
				(width 0.05)
				(type solid)
			)
			(fill no)
			(layer "F.CrtYd")
		)
		(fp_line
			(start -1.266 -1.067)
			(end -0.758 -1.625)
			(stroke
				(width 0.15)
				(type solid)
			)
			(layer "F.Fab")
		)
		(fp_line
			(start -1.266 1.677)
			(end -1.266 -1.067)
			(stroke
				(width 0.15)
				(type solid)
			)
			(layer "F.Fab")
		)
		(fp_line
			(start -1.266 1.677)
			(end 1.269 1.677)
			(stroke
				(width 0.15)
				(type solid)
			)
			(layer "F.Fab")
		)
		(fp_line
			(start 1.269 -1.625)
			(end -0.758 -1.625)
			(stroke
				(width 0.15)
				(type solid)
			)
			(layer "F.Fab")
		)
		(fp_line
			(start 1.269 1.677)
			(end 1.269 -1.625)
			(stroke
				(width 0.15)
				(type solid)
			)
			(layer "F.Fab")
		)
		(fp_text user "${REFERENCE}"
			(at -1.746 5.099 0)
			(unlocked yes)
			(layer "F.Fab")
			(effects
				(font
					(size 0.7 0.7)
					(thickness 0.15)
				)
				(justify left bottom)
			)
		)
		(fp_text user "Author: Antmicro"
			(at -1.746 6.299 0)
			(layer "F.Fab")
			(effects
				(font
					(size 0.7 0.7)
					(thickness 0.15)
				)
				(justify left bottom)
			)
		)
		(fp_text user "License: Apache-2.0"
			(at -1.746 7.499 0)
			(layer "F.Fab")
			(effects
				(font
					(size 0.7 0.7)
					(thickness 0.15)
				)
				(justify left bottom)
			)
		)
		(pad "1" smd rect
			(at -1.3 -0.762 90)
			(size 0.3 0.7)
			(layers "F.Cu" "F.Mask" "F.Paste")
			(net 134 "+3V3")
			(pinfunction "OE")
			(pintype "input")
		)
		(pad "2" smd rect
			(at -1.3 -0.25 90)
			(size 0.3 0.7)
			(layers "F.Cu" "F.Mask" "F.Paste")
			(net 195 "unconnected-(U7-NC-Pad2)")
			(pinfunction "NC")
			(pintype "no_connect")
		)
		(pad "3" smd rect
			(at -1.3 0.25 90)
			(size 0.3 0.7)
			(layers "F.Cu" "F.Mask" "F.Paste")
			(net 189 "unconnected-(U7-NC-Pad3)")
			(pinfunction "NC")
			(pintype "no_connect")
		)
		(pad "4" smd rect
			(at -1.3 0.75 90)
			(size 0.3 0.7)
			(layers "F.Cu" "F.Mask" "F.Paste")
			(net 66 "GND")
			(pinfunction "VSS")
			(pintype "power_in")
		)
		(pad "5" smd rect
			(at -0.5 1.65)
			(size 0.3 0.7)
			(layers "F.Cu" "F.Mask" "F.Paste")
			(net 190 "unconnected-(U7-NC-Pad5)")
			(pinfunction "NC")
			(pintype "no_connect")
		)
		(pad "6" smd rect
			(at 0 1.65)
			(size 0.3 0.7)
			(layers "F.Cu" "F.Mask" "F.Paste")
			(net 192 "unconnected-(U7-NC-Pad6)")
			(pinfunction "NC")
			(pintype "no_connect")
		)
		(pad "7" smd rect
			(at 0.5 1.65)
			(size 0.3 0.7)
			(layers "F.Cu" "F.Mask" "F.Paste")
			(net 196 "unconnected-(U7-NC-Pad7)")
			(pinfunction "NC")
			(pintype "no_connect")
		)
		(pad "8" smd rect
			(at 1.3 0.75 270)
			(size 0.3 0.7)
			(layers "F.Cu" "F.Mask" "F.Paste")
			(net 197 "/PCIe-clock-generator/PCIe_{REF1}_R2.CK+")
			(pinfunction "CLK1+")
			(pintype "output")
		)
		(pad "9" smd rect
			(at 1.3 0.25 270)
			(size 0.3 0.7)
			(layers "F.Cu" "F.Mask" "F.Paste")
			(net 198 "/PCIe-clock-generator/PCIe_{REF1}_R2.CK-")
			(pinfunction "CLK1-")
			(pintype "output")
		)
		(pad "10" smd rect
			(at 1.3 -0.25 270)
			(size 0.3 0.7)
			(layers "F.Cu" "F.Mask" "F.Paste")
			(net 194 "unconnected-(U7-CLK0--Pad10)")
			(pinfunction "CLK0-")
			(pintype "output+no_connect")
		)
		(pad "11" smd rect
			(at 1.3 -0.75 270)
			(size 0.3 0.7)
			(layers "F.Cu" "F.Mask" "F.Paste")
			(net 191 "unconnected-(U7-CLK0+-Pad11)")
			(pinfunction "CLK0+")
			(pintype "output+no_connect")
		)
		(pad "12" smd rect
			(at 0.5 -1.65 180)
			(size 0.3 0.7)
			(layers "F.Cu" "F.Mask" "F.Paste")
			(net 134 "+3V3")
			(pinfunction "VDD1")
			(pintype "power_in")
		)
		(pad "13" smd rect
			(at 0 -1.65 180)
			(size 0.3 0.7)
			(layers "F.Cu" "F.Mask" "F.Paste")
			(net 134 "+3V3")
			(pinfunction "VDD0")
			(pintype "power_in")
		)
		(pad "14" smd rect
			(at -0.5 -1.65 180)
			(size 0.3 0.7)
			(layers "F.Cu" "F.Mask" "F.Paste")
			(net 193 "unconnected-(U7-NC-Pad14)")
			(pinfunction "NC")
			(pintype "no_connect")
		)
		(pad "15" smd roundrect
			(at 0.003 0 90)
			(size 2.1 1.4)
			(layers "F.Cu" "F.Mask" "F.Paste")
			(roundrect_rratio 0)
			(chamfer_ratio 0.2)
			(chamfer top_right)
			(net 66 "GND")
			(pinfunction "EPAD")
			(pintype "passive")
		)
	)
)
